(kicad_pcb
	(version 20260206)
	(generator "pcbnew")
	(generator_version "10.0")
	(general
		(thickness 1.6)
		(legacy_teardrops no)
	)
	(paper "A4")
	(title_block
		(title "04192023_DAF0TMB3IC0_F0TG_MB_C_brd_V02_OCP.brd")
		(comment 1 "Grand Teton / footprints 1342-1344 of 8354")
	)
	(layers
		(0 "F.Cu" signal "TOP")
		(4 "In1.Cu" signal "GND")
		(6 "In2.Cu" signal "IN1")
		(8 "In3.Cu" signal "GND1")
		(10 "In4.Cu" signal "IN2")
		(12 "In5.Cu" signal "GND2")
		(14 "In6.Cu" signal "IN3")
		(16 "In7.Cu" signal "GND3")
		(18 "In8.Cu" signal "VCC")
		(20 "In9.Cu" signal "VCC1")
		(22 "In10.Cu" signal "GND4")
		(24 "In11.Cu" signal "IN4")
		(26 "In12.Cu" signal "GND5")
		(28 "In13.Cu" signal "IN5")
		(30 "In14.Cu" signal "GND6")
		(32 "In15.Cu" signal "IN6")
		(34 "In16.Cu" signal "GND7")
		(2 "B.Cu" signal "BOTTOM")
		(9 "F.Adhes" user "F.Adhesive")
		(11 "B.Adhes" user "B.Adhesive")
		(13 "F.Paste" user "Package Geometry/Pastemask Top")
		(15 "B.Paste" user "Package Geometry/Pastemask Bottom")
		(5 "F.SilkS" user "Ref Des/Silkscreen Top")
		(7 "B.SilkS" user "Ref Des/Silkscreen Bottom")
		(1 "F.Mask" user "Board Geometry/Soldermask Top")
		(3 "B.Mask" user "Board Geometry/Soldermask Bottom")
		(17 "Dwgs.User" user "User.Drawings")
		(19 "Cmts.User" user "User.Comments")
		(21 "Eco1.User" user "User.Eco1")
		(23 "Eco2.User" user "User.Eco2")
		(25 "Edge.Cuts" user "Board Geometry/Outline")
		(27 "Margin" user)
		(31 "F.CrtYd" user "Package Geometry/Place Bound Top")
		(29 "B.CrtYd" user "Package Geometry/Place Bound Bottom")
		(35 "F.Fab" user "Ref Des/Assembly Top")
		(33 "B.Fab" user "Ref Des/Assembly Bottom")
	)
	(footprint ""
		(layer "F.Cu")
		(at 30.48 -364.109 -90)
		(property "Reference" "PU34"
			(at 3.80873 0.935736 0)
			(unlocked yes)
			(layer "F.SilkS")
			(effects
				(font
					(size 0.7874 0.5842)
					(thickness 0.1524)
				)
			)
		)
		(property "Value" ""
			(at 0 0 270)
			(layer "F.Fab")
			(effects
				(font
					(size 1.27 1.27)
				)
			)
		)
		(duplicate_pad_numbers_are_jumpers no)
		(fp_line
			(start -3.024886 3.024886)
			(end -3.024886 2.428494)
			(stroke
				(width 0.1524)
				(type default)
			)
			(layer "F.SilkS")
		)
		(fp_line
			(start -2.428494 3.024886)
			(end -3.024886 3.024886)
			(stroke
				(width 0.1524)
				(type default)
			)
			(layer "F.SilkS")
		)
		(fp_line
			(start 3.024886 3.024886)
			(end 2.428494 3.024886)
			(stroke
				(width 0.1524)
				(type default)
			)
			(layer "F.SilkS")
		)
		(fp_line
			(start 3.024886 2.428494)
			(end 3.024886 3.024886)
			(stroke
				(width 0.1524)
				(type default)
			)
			(layer "F.SilkS")
		)
		(fp_line
			(start -3.024886 -2.428494)
			(end -3.024886 -3.024886)
			(stroke
				(width 0.1524)
				(type default)
			)
			(layer "F.SilkS")
		)
		(fp_line
			(start -3.024886 -3.024886)
			(end -2.428494 -3.024886)
			(stroke
				(width 0.1524)
				(type default)
			)
			(layer "F.SilkS")
		)
		(fp_line
			(start 2.428494 -3.024886)
			(end 3.024886 -3.024886)
			(stroke
				(width 0.1524)
				(type default)
			)
			(layer "F.SilkS")
		)
		(fp_line
			(start 3.024886 -3.024886)
			(end 3.024886 -2.428494)
			(stroke
				(width 0.1524)
				(type default)
			)
			(layer "F.SilkS")
		)
		(fp_poly
			(pts
				(xy -4.348226 -2.707894) (xy -4.348226 -1.691894) (xy -3.332226 -2.199894)
			)
			(stroke
				(width 0)
				(type default)
			)
			(fill yes)
			(layer "F.SilkS")
		)
		(fp_line
			(start -3.024886 3.024886)
			(end -3.024886 -3.024886)
			(stroke
				(width 0.1)
				(type default)
			)
			(layer "F.Fab")
		)
		(fp_line
			(start 3.024886 3.024886)
			(end -3.024886 3.024886)
			(stroke
				(width 0.1)
				(type default)
			)
			(layer "F.Fab")
		)
		(fp_line
			(start -3.024886 -3.024886)
			(end 3.024886 -3.024886)
			(stroke
				(width 0.1)
				(type default)
			)
			(layer "F.Fab")
		)
		(fp_line
			(start 3.024886 -3.024886)
			(end 3.024886 3.024886)
			(stroke
				(width 0.1)
				(type default)
			)
			(layer "F.Fab")
		)
		(fp_poly
			(pts
				(xy -3.332226 -2.199894) (xy -4.348226 -1.691894) (xy -4.348226 -2.707894)
			)
			(stroke
				(width 0)
				(type default)
			)
			(fill yes)
			(layer "F.Fab")
		)
		(pad "1" smd rect
			(at -2.875026 -2.199894 180)
			(size 0.1778 0.6604)
			(layers "F.Cu" "F.Mask" "F.Paste")
			(net "PVDDIO_P1_PWM1")
		)
		(pad "2" smd rect
			(at -2.875026 -1.800098 180)
			(size 0.1778 0.6604)
			(layers "F.Cu" "F.Mask" "F.Paste")
			(net "PVDDIO_P1_PWM2")
		)
		(pad "3" smd rect
			(at -2.875026 -1.400048 180)
			(size 0.1778 0.6604)
			(layers "F.Cu" "F.Mask" "F.Paste")
			(net "PVDDIO_P1_PWM3")
		)
		(pad "4" smd rect
			(at -2.875026 -0.999998 180)
			(size 0.1778 0.6604)
			(layers "F.Cu" "F.Mask" "F.Paste")
			(net "PVDDIO_P1_PWM4")
		)
		(pad "5" smd rect
			(at -2.875026 -0.599948 180)
			(size 0.1778 0.6604)
			(layers "F.Cu" "F.Mask" "F.Paste")
			(net "NC_PVDDCR_CPU1_P1_PWM8")
		)
		(pad "6" smd rect
			(at -2.875026 -0.199898 180)
			(size 0.1778 0.6604)
			(layers "F.Cu" "F.Mask" "F.Paste")
			(net "NC_PVDDCR_CPU1_P1_PWM7")
		)
		(pad "7" smd rect
			(at -2.875026 0.199898 180)
			(size 0.1778 0.6604)
			(layers "F.Cu" "F.Mask" "F.Paste")
			(net "PVDDCR_CPU1_P1_PWM6")
		)
		(pad "8" smd rect
			(at -2.875026 0.599948 180)
			(size 0.1778 0.6604)
			(layers "F.Cu" "F.Mask" "F.Paste")
			(net "PVDDCR_CPU1_P1_PWM5")
		)
		(pad "9" smd rect
			(at -2.875026 0.999998 180)
			(size 0.1778 0.6604)
			(layers "F.Cu" "F.Mask" "F.Paste")
			(net "PVDDCR_CPU1_P1_PWM4")
		)
		(pad "10" smd rect
			(at -2.875026 1.400048 180)
			(size 0.1778 0.6604)
			(layers "F.Cu" "F.Mask" "F.Paste")
			(net "PVDDCR_CPU1_P1_PWM3")
		)
		(pad "11" smd rect
			(at -2.875026 1.800098 180)
			(size 0.1778 0.6604)
			(layers "F.Cu" "F.Mask" "F.Paste")
			(net "PVDDCR_CPU1_P1_PWM2")
		)
		(pad "12" smd rect
			(at -2.875026 2.199894 180)
			(size 0.1778 0.6604)
			(layers "F.Cu" "F.Mask" "F.Paste")
			(net "PVDDCR_CPU1_P1_PWM1")
		)
		(pad "13" smd rect
			(at -2.199894 2.875026 270)
			(size 0.1778 0.6604)
			(layers "F.Cu" "F.Mask" "F.Paste")
			(net "SMB_DIO_PVDDCR_CPU1_P1_R")
		)
		(pad "14" smd rect
			(at -1.800098 2.875026 270)
			(size 0.1778 0.6604)
			(layers "F.Cu" "F.Mask" "F.Paste")
			(net "SMB_CLK_PVDDCR_CPU1_P1_R")
		)
		(pad "15" smd rect
			(at -1.400048 2.875026 270)
			(size 0.1778 0.6604)
			(layers "F.Cu" "F.Mask" "F.Paste")
			(net "PVDDCR_CPU1_P1_SMB_ALERT_R")
		)
		(pad "16" smd rect
			(at -0.999998 2.875026 270)
			(size 0.1778 0.6604)
			(layers "F.Cu" "F.Mask" "F.Paste")
			(net "PWRGD_PVDDCR_CPU1_P1_R")
		)
		(pad "17" smd rect
			(at -0.599948 2.875026 270)
			(size 0.1778 0.6604)
			(layers "F.Cu" "F.Mask" "F.Paste")
			(net "PVDDCR_CPU1_P1_EN_R")
		)
		(pad "18" smd rect
			(at -0.199898 2.875026 270)
			(size 0.1778 0.6604)
			(layers "F.Cu" "F.Mask" "F.Paste")
			(net "PVDDCR_CPU1_P1_RESET_N_R")
		)
		(pad "19" smd rect
			(at 0.199898 2.875026 270)
			(size 0.1778 0.6604)
			(layers "F.Cu" "F.Mask" "F.Paste")
			(net "PVDD18_S5_P1")
		)
		(pad "20" smd rect
			(at 0.599948 2.875026 270)
			(size 0.1778 0.6604)
			(layers "F.Cu" "F.Mask" "F.Paste")
			(net "PWRGD_PVDDIO_P1_R")
		)
		(pad "21" smd rect
			(at 0.999998 2.875026 270)
			(size 0.1778 0.6604)
			(layers "F.Cu" "F.Mask" "F.Paste")
			(net "SVID_PVDDCR_CPU1_P1_SVD_R1")
		)
		(pad "22" smd rect
			(at 1.400048 2.875026 270)
			(size 0.1778 0.6604)
			(layers "F.Cu" "F.Mask" "F.Paste")
			(net "SVID_PVDDCR_CPU1_P1_SVC_R1")
		)
		(pad "23" smd rect
			(at 1.800098 2.875026 270)
			(size 0.1778 0.6604)
			(layers "F.Cu" "F.Mask" "F.Paste")
			(net "SVID_PVDDCR_CPU1_P1_SVTO_R")
		)
		(pad "24" smd rect
			(at 2.199894 2.875026 270)
			(size 0.1778 0.6604)
			(layers "F.Cu" "F.Mask" "F.Paste")
			(net "SVID_PVDDCR_CPU1_P1_SVTI_R")
		)
		(pad "25" smd rect
			(at 2.875026 2.199894 180)
			(size 0.1778 0.6604)
			(layers "F.Cu" "F.Mask" "F.Paste")
			(net "VSENSE_PVDDCR_CPU1_P1_VSEN0")
		)
		(pad "26" smd rect
			(at 2.875026 1.800098 180)
			(size 0.1778 0.6604)
			(layers "F.Cu" "F.Mask" "F.Paste")
			(net "VSENSE_VSS_SENSE_C_P1")
		)
		(pad "27" smd rect
			(at 2.875026 1.400048 180)
			(size 0.1778 0.6604)
			(layers "F.Cu" "F.Mask" "F.Paste")
			(net "PVDDCR_CPU1_P1_IMON1")
		)
		(pad "28" smd rect
			(at 2.875026 0.999998 180)
			(size 0.1778 0.6604)
			(layers "F.Cu" "F.Mask" "F.Paste")
			(net "PVDDCR_CPU1_P1_IMON2")
		)
		(pad "29" smd rect
			(at 2.875026 0.599948 180)
			(size 0.1778 0.6604)
			(layers "F.Cu" "F.Mask" "F.Paste")
			(net "PVDDCR_CPU1_P1_IMON3")
		)
		(pad "30" smd rect
			(at 2.875026 0.199898 180)
			(size 0.1778 0.6604)
			(layers "F.Cu" "F.Mask" "F.Paste")
			(net "PVDDCR_CPU1_P1_IMON4")
		)
		(pad "31" smd rect
			(at 2.875026 -0.199898 180)
			(size 0.1778 0.6604)
			(layers "F.Cu" "F.Mask" "F.Paste")
			(net "PVDDCR_CPU1_P1_IMON5")
		)
		(pad "32" smd rect
			(at 2.875026 -0.599948 180)
			(size 0.1778 0.6604)
			(layers "F.Cu" "F.Mask" "F.Paste")
			(net "PVDDCR_CPU1_P1_IMON6")
		)
		(pad "33" smd rect
			(at 2.875026 -0.999998 180)
			(size 0.1778 0.6604)
			(layers "F.Cu" "F.Mask" "F.Paste")
			(net "NC_PVDDCR_CPU1_P1_IMON7")
		)
		(pad "34" smd rect
			(at 2.875026 -1.400048 180)
			(size 0.1778 0.6604)
			(layers "F.Cu" "F.Mask" "F.Paste")
			(net "NC_PVDDCR_CPU1_P1_IMON8")
		)
		(pad "35" smd rect
			(at 2.875026 -1.800098 180)
			(size 0.1778 0.6604)
			(layers "F.Cu" "F.Mask" "F.Paste")
			(net "PVDDIO_P1_IMON4")
		)
		(pad "36" smd rect
			(at 2.875026 -2.199894 180)
			(size 0.1778 0.6604)
			(layers "F.Cu" "F.Mask" "F.Paste")
			(net "PVDDIO_P1_IMON3")
		)
		(pad "37" smd rect
			(at 2.199894 -2.875026 270)
			(size 0.1778 0.6604)
			(layers "F.Cu" "F.Mask" "F.Paste")
			(net "PVDDIO_P1_IMON2")
		)
		(pad "38" smd rect
			(at 1.800098 -2.875026 270)
			(size 0.1778 0.6604)
			(layers "F.Cu" "F.Mask" "F.Paste")
			(net "PVDDIO_P1_IMON1")
		)
		(pad "39" smd rect
			(at 1.400048 -2.875026 270)
			(size 0.1778 0.6604)
			(layers "F.Cu" "F.Mask" "F.Paste")
			(net "VSENSE_VSS_SENSE_B_P1")
		)
		(pad "40" smd rect
			(at 0.999998 -2.875026 270)
			(size 0.1778 0.6604)
			(layers "F.Cu" "F.Mask" "F.Paste")
			(net "VSENSE_PVDDIO_P1_VSEN1")
		)
		(pad "41" smd rect
			(at 0.599948 -2.875026 270)
			(size 0.1778 0.6604)
			(layers "F.Cu" "F.Mask" "F.Paste")
			(net "PVDDCR_CPU1_P1_OCP_N_R")
		)
		(pad "42" smd rect
			(at 0.199898 -2.875026 270)
			(size 0.1778 0.6604)
			(layers "F.Cu" "F.Mask" "F.Paste")
			(net "PVDDCR_CPU1_P1_EN1_ADDR_CFG")
		)
		(pad "43" smd rect
			(at -0.199898 -2.875026 270)
			(size 0.1778 0.6604)
			(layers "F.Cu" "F.Mask" "F.Paste")
			(net "PVDDIO_P1_TEMP1")
		)
		(pad "44" smd rect
			(at -0.599948 -2.875026 270)
			(size 0.1778 0.6604)
			(layers "F.Cu" "F.Mask" "F.Paste")
			(net "PVDDCR_CPU1_P1_TEMP0")
		)
		(pad "45" smd rect
			(at -0.999998 -2.875026 270)
			(size 0.1778 0.6604)
			(layers "F.Cu" "F.Mask" "F.Paste")
			(net "PVDDCR_CPU1_P1_VMON")
		)
		(pad "46" smd rect
			(at -1.400048 -2.875026 270)
			(size 0.1778 0.6604)
			(layers "F.Cu" "F.Mask" "F.Paste")
			(net "PVDDCR_CPU1_P1_VINSEN")
		)
		(pad "47" smd rect
			(at -1.800098 -2.875026 270)
			(size 0.1778 0.6604)
			(layers "F.Cu" "F.Mask" "F.Paste")
			(net "PVDDCR_CPU1_P1_VCC")
		)
		(pad "48" smd rect
			(at -2.199894 -2.875026 270)
			(size 0.1778 0.6604)
			(layers "F.Cu" "F.Mask" "F.Paste")
			(net "PVDDCR_CPU1_P1_VCCS")
		)
		(pad "TH" smd rect
			(at 0 0 270)
			(size 4.4196 4.4196)
			(layers "F.Cu" "F.Mask" "F.Paste")
			(net "GND")
		)
		(zone
			(layer "F.Cu")
			(hatch none 0.5)
			(connect_pads
				(clearance 0)
			)
			(min_thickness 0.25)
			(keepout
				(tracks not_allowed)
				(vias allowed)
				(pads allowed)
				(copperpour not_allowed)
				(footprints allowed)
			)
			(placement
				(enabled no)
				(sheetname "")
			)
			(fill
				(thermal_gap 0.5)
				(thermal_bridge_width 0.5)
				(island_removal_mode 0)
			)
			(polygon
				(pts
					(xy 30.5054 -366.603026) (xy 32.974026 -366.603026) (xy 32.974026 -361.614974) (xy 27.985974 -361.614974)
					(xy 27.985974 -366.603026) (xy 30.48 -366.603026) (xy 30.48 -366.3696) (xy 28.2194 -366.3696) (xy 28.2194 -361.8484)
					(xy 32.7406 -361.8484) (xy 32.7406 -366.3696) (xy 30.5054 -366.3696)
				)
			)
		)
	)
	(footprint ""
		(layer "F.Cu")
		(at 115.389152 -401.353782 180)
		(property "Reference" "U42"
			(at -0.873252 -3.739642 0)
			(unlocked yes)
			(layer "F.SilkS")
			(effects
				(font
					(size 0.7874 0.5842)
					(thickness 0.1524)
				)
			)
		)
		(property "Value" ""
			(at 0 0 180)
			(layer "F.Fab")
			(effects
				(font
					(size 1.27 1.27)
				)
			)
		)
		(duplicate_pad_numbers_are_jumpers no)
		(fp_line
			(start 1.03378 1.284478)
			(end -1.03378 1.284478)
			(stroke
				(width 0.1524)
				(type default)
			)
			(layer "F.SilkS")
		)
		(fp_line
			(start 1.03378 -1.284478)
			(end 1.03378 1.284478)
			(stroke
				(width 0.1524)
				(type default)
			)
			(layer "F.SilkS")
		)
		(fp_line
			(start -1.03378 1.284478)
			(end -1.03378 -1.284478)
			(stroke
				(width 0.1524)
				(type default)
			)
			(layer "F.SilkS")
		)
		(fp_line
			(start -1.03378 -1.284478)
			(end 1.03378 -1.284478)
			(stroke
				(width 0.1524)
				(type default)
			)
			(layer "F.SilkS")
		)
		(fp_poly
			(pts
				(xy -1.176274 -0.652272) (xy -1.478788 -0.047244) (xy -1.841754 -0.531114)
			)
			(stroke
				(width 0)
				(type default)
			)
			(fill yes)
			(layer "F.SilkS")
		)
		(fp_line
			(start 0.774954 1.02489)
			(end -0.774954 1.02489)
			(stroke
				(width 0.1)
				(type default)
			)
			(layer "F.Fab")
		)
		(fp_line
			(start 0.774954 -1.02489)
			(end 0.774954 1.02489)
			(stroke
				(width 0.1)
				(type default)
			)
			(layer "F.Fab")
		)
		(fp_line
			(start -0.774954 1.02489)
			(end -0.774954 -1.02489)
			(stroke
				(width 0.1)
				(type default)
			)
			(layer "F.Fab")
		)
		(fp_line
			(start -0.774954 -1.02489)
			(end 0.774954 -1.02489)
			(stroke
				(width 0.1)
				(type default)
			)
			(layer "F.Fab")
		)
		(fp_poly
			(pts
				(xy -1.201674 -0.750062) (xy -1.806702 -0.447548) (xy -1.806702 -1.052576)
			)
			(stroke
				(width 0)
				(type default)
			)
			(fill yes)
			(layer "F.Fab")
		)
		(pad "1" smd rect
			(at -0.64008 -0.750062 270)
			(size 0.3048 0.5334)
			(layers "F.Cu" "F.Mask" "F.Paste")
			(net "SMB_RT_CPU1_P1_ROM_MUX_1D_SCL")
		)
		(pad "2" smd rect
			(at -0.64008 -0.249936 270)
			(size 0.254 0.5334)
			(layers "F.Cu" "F.Mask" "F.Paste")
			(net "SMB_RT_CPU1_P1_ROM_MUX_1D_SDA")
		)
		(pad "3" smd rect
			(at -0.64008 0.249936 270)
			(size 0.254 0.5334)
			(layers "F.Cu" "F.Mask" "F.Paste")
			(net "SMB_RT_CPU1_P1_ROM_MUX_2D_SCL")
		)
		(pad "4" smd rect
			(at -0.64008 0.750062 270)
			(size 0.3048 0.5334)
			(layers "F.Cu" "F.Mask" "F.Paste")
			(net "SMB_RT_CPU1_P1_ROM_MUX_2D_SDA")
		)
		(pad "5" smd rect
			(at 0 0.839978 180)
			(size 0.3302 0.635)
			(layers "F.Cu" "F.Mask" "F.Paste")
			(net "GND")
		)
		(pad "6" smd rect
			(at 0.64008 0.750062 270)
			(size 0.3048 0.5334)
			(layers "F.Cu" "F.Mask" "F.Paste")
			(net "RT_ROM_MUX2_OE_N")
		)
		(pad "7" smd rect
			(at 0.64008 0.249936 270)
			(size 0.254 0.5334)
			(layers "F.Cu" "F.Mask" "F.Paste")
			(net "SMB_RT_CPU1_P1_ROM_R_SDA")
		)
		(pad "8" smd rect
			(at 0.64008 -0.249936 270)
			(size 0.254 0.5334)
			(layers "F.Cu" "F.Mask" "F.Paste")
			(net "SMB_RT_CPU1_P1_ROM_R_SCL")
		)
		(pad "9" smd rect
			(at 0.64008 -0.750062 270)
			(size 0.3048 0.5334)
			(layers "F.Cu" "F.Mask" "F.Paste")
			(net "FM_SMB_RT_ROM_MUX2_SEL")
		)
		(pad "10" smd rect
			(at 0 -0.839978 180)
			(size 0.3302 0.635)
			(layers "F.Cu" "F.Mask" "F.Paste")
			(net "P3V3_AUX")
		)
	)
	(footprint ""
		(layer "F.Cu")
		(at 40.386 -389.0264 -90)
		(property "Reference" "R6724"
			(at 0 0 270)
			(layer "F.SilkS")
			(hide yes)
			(effects
				(font
					(size 1.27 1.27)
				)
			)
		)
		(property "Value" ""
			(at 0 0 270)
			(layer "F.Fab")
			(effects
				(font
					(size 1.27 1.27)
				)
			)
		)
		(duplicate_pad_numbers_are_jumpers no)
		(fp_line
			(start -0.32512 0.175006)
			(end -0.32512 -0.175006)
			(stroke
				(width 0.1)
				(type default)
			)
			(layer "F.Fab")
		)
		(fp_line
			(start 0.32512 0.175006)
			(end -0.32512 0.175006)
			(stroke
				(width 0.1)
				(type default)
			)
			(layer "F.Fab")
		)
		(fp_line
			(start -0.32512 -0.175006)
			(end 0.32512 -0.175006)
			(stroke
				(width 0.1)
				(type default)
			)
			(layer "F.Fab")
		)
		(fp_line
			(start 0.32512 -0.175006)
			(end 0.32512 0.175006)
			(stroke
				(width 0.1)
				(type default)
			)
			(layer "F.Fab")
		)
		(pad "1" smd rect
			(at -0.2667 0 270)
			(size 0.3048 0.381)
			(layers "F.Cu" "F.Mask" "F.Paste")
			(net "P1V8_CPU1_RT_1D")
		)
		(pad "2" smd rect
			(at 0.2667 0 90)
			(size 0.3048 0.381)
			(layers "F.Cu" "F.Mask" "F.Paste")
			(net "RST_RT_CPU1_P0_RESET_R_N")
		)
	)
)
